FILE_TYPE = CONNECTIVITY;
{Allegro Design Entry HDL 16.6-p007 (v16-6-112F) 10/10/2012}
"PAGE_NUMBER" = 164;
0"NC";
1"P3V3_STBY\g";
2"P3V3_STBY\g";
3"GND\g";
4"GND\g";
5"P3V3_STBY\g";
6"GND\g";
7"P3V3_STBY\g";
8"GND\g";
9"GND\g";
10"GND\g";
11"P3V3_STBY\g";
12"GND\g";
13"FM_BOARD_SKU_ID2";
14"FM_BOARD_SKU_ID0";
15"PCA9554_A2";
16"FM_BOARD_REV_ID1";
17"FM_BOARD_REV_ID0";
18"PCA9554_INT_N";
19"PCA9554_A2";
20"PCA9554_A1";
21"FM_CPU_BMC_INIT";
22"FM_MB_SLOT_ID2";
23"SMB_SENSOR_STBY_LVC3_SCL";
24"PCA9554_A0";
25"PCA9554_A0";
26"SMB_SENSOR_STBY_LVC3_SDA";
27"FM_MB_SLOT_ID1";
28"FM_MB_SLOT_ID0";
29"PCA9554_A1";
30"FM_BOARD_REV_ID2";
31"FM_BOARD_SKU_ID1";
32"FM_BOARD_SKU_ID3";
33"FM_BOARD_SKU_ID4";
%"RES"
"1","(-7400,1200)","0","mstr_discrete","I100";
;
PACK_TYPE"0402"
MATERIAL"CHIP"
PART_NUMBER"G21796-344"
VALUE"2.7K"
TOLERANCE"1%"
WATTAGE"1/16W"
LOCATION"R1T4"
CDS_LOCATION"R1T4"
CDS_SEC"1"
CDS_LIB"mstr_discrete"
SEC_TYPE"0402"
SEC"1"
ROOM"BMC_MISC"
BOM_COST"SM_CONTROLLER";
"B"
$PN"2"17;
"A"
$PN"1"1;
%"RES"
"2","(-6250,925)","0","mstr_discrete","I101";
;
PART_NUMBER"G21796-026"
POP"NOPOP"
PACK_TYPE"0402"
MATERIAL"CHIP"
WATTAGE"1/16W"
LOCATION"R1T10"
TOLERANCE"1%"
VALUE"1.00K"
CDS_LOCATION"R1T10"
ROOM"BMC_MISC"
CDS_LIB"mstr_discrete"
BOM_COST"SM_CONTROLLER"
SEC_TYPE"0402"
SEC"1"
CDS_SEC"1";
"A"
$PN"1"17;
"B"
$PN"2"12;
%"RES"
"1","(-7400,1600)","0","mstr_discrete","I11";
;
CDS_SEC"1"
WATTAGE"1/16W"
TOLERANCE"1%"
MATERIAL"EMPTY"
PART_NUMBER"G21796-344"
PACK_TYPE"0402"
LOCATION"R1T5"
VALUE"2.7K"
SEC_TYPE"0402"
BOM_COST"SM_CONTROLLER"
SEC"1"
ROOM"BMC_MISC"
CDS_LOCATION"R1T5"
CDS_LIB"mstr_discrete";
"B"
$PN"2"30;
"A"
$PN"1"1;
%"P3V3_STBY"
"1","(-7750,1750)","0","mstr_symbols","I12";
;
HDL_POWER"P3V3_STBY"
BODY_TYPE"PLUMBING"
VOLTAGE"3.3V"
SIZE"1B"
CDS_LIB"mstr_symbols";
"G\NAC"1;
%"RES"
"2","(-6025,3350)","0","mstr_discrete","I21";
;
CDS_SEC"1"
PACK_TYPE"0402"
WATTAGE"1/16W"
VALUE"1.00K"
LOCATION"R1U17"
PART_NUMBER"G21796-026"
MATERIAL"CHIP"
TOLERANCE"1%"
BOM_COST"SM_CONTROLLER"
ROOM"BMC_MISC"
SEC_TYPE"0402"
SEC"1"
CDS_LIB"mstr_discrete"
CDS_LOCATION"R1U17";
"A"
$PN"1"13;
"B"
$PN"2"3;
%"P3V3_STBY"
"1","(-7525,4650)","0","mstr_symbols","I26";
;
HDL_POWER"P3V3_STBY"
BODY_TYPE"PLUMBING"
VOLTAGE"3.3V"
CDS_LIB"mstr_symbols"
SIZE"1B";
"G\NAC"2;
%"GND"
"1","(-6625,3050)","0","mstr_symbols","I31";
;
HDL_POWER"GND"
BODY_TYPE"PLUMBING"
SIZE"1B"
VOLTAGE"0.0V"
CDS_LIB"mstr_symbols";
"A\NAC"3;
%"RES"
"2","(-6625,3350)","0","mstr_discrete","I32";
;
CDS_SEC"1"
PACK_TYPE"0402"
LOCATION"R2N18"
TOLERANCE"1%"
WATTAGE"1/16W"
GROUP"PD_SKU_ID4"
MATERIAL"CHIP"
PART_NUMBER"G21796-026"
VALUE"1.00K"
CDS_LIB"mstr_discrete"
CDS_LOCATION"R2N18"
BOM_COST"SM_CONTROLLER"
ROOM"BMC_MISC"
SEC"1"
SEC_TYPE"0402";
"A"
$PN"1"33;
"B"
$PN"2"3;
%"RES"
"1","(-7175,3675)","0","mstr_discrete","I34";
;
PACK_TYPE"0402"
GROUP"PU_SKU_ID0"
MATERIAL"CHIP"
TOLERANCE"1%"
WATTAGE"1/16W"
LOCATION"R1U23"
VALUE"2.7K"
PART_NUMBER"G21796-344"
BOM_COST"SM_CONTROLLER"
ROOM"BMC_MISC"
SEC"1"
SEC_TYPE"0402"
CDS_LOCATION"R1U23"
CDS_LIB"mstr_discrete"
CDS_SEC"1";
"B"
$PN"2"14;
"A"
$PN"1"2;
%"RES"
"2","(-5725,3350)","0","mstr_discrete","I37";
;
CDS_SEC"1"
GROUP"PD_SKU_ID1"
MATERIAL"CHIP"
PART_NUMBER"G21796-026"
PACK_TYPE"0402"
WATTAGE"1/16W"
TOLERANCE"1%"
VALUE"1.00K"
LOCATION"R1U16"
CDS_LOCATION"R1U16"
ROOM"BMC_MISC"
SEC"1"
BOM_COST"SM_CONTROLLER"
SEC_TYPE"0402"
CDS_LIB"mstr_discrete";
"A"
$PN"1"31;
"B"
$PN"2"3;
%"RES"
"2","(-5425,3350)","0","mstr_discrete","I40";
;
CDS_SEC"1"
GROUP"PD_SKU_ID0"
TOLERANCE"1%"
VALUE"1.00K"
LOCATION"R1U18"
MATERIAL"CHIP"
WATTAGE"1/16W"
PART_NUMBER"G21796-026"
PACK_TYPE"0402"
CDS_LOCATION"R1U18"
ROOM"BMC_MISC"
SEC"1"
BOM_COST"SM_CONTROLLER"
SEC_TYPE"0402"
CDS_LIB"mstr_discrete";
"A"
$PN"1"14;
"B"
$PN"2"3;
%"RES"
"1","(-7175,4275)","0","mstr_discrete","I41";
;
VALUE"2.7K"
LOCATION"R1U21"
TOLERANCE"1%"
PART_NUMBER"G21796-344"
WATTAGE"1/16W"
GROUP"PU_SKU_ID3"
MATERIAL"CHIP"
PACK_TYPE"0402"
CDS_SEC"1"
CDS_LIB"mstr_discrete"
SEC_TYPE"0402"
SEC"1"
ROOM"BMC_MISC"
BOM_COST"SM_CONTROLLER"
CDS_LOCATION"R1U21";
"B"
$PN"2"32;
"A"
$PN"1"2;
%"RES"
"1","(-7175,3875)","0","mstr_discrete","I43";
;
PACK_TYPE"0402"
VALUE"2.7K"
TOLERANCE"1%"
LOCATION"R1U22"
PART_NUMBER"G21796-344"
WATTAGE"1/16W"
MATERIAL"CHIP"
GROUP"PU_SKU_ID1"
CDS_LOCATION"R1U22"
CDS_SEC"1"
CDS_LIB"mstr_discrete"
SEC_TYPE"0402"
SEC"1"
ROOM"BMC_MISC"
BOM_COST"SM_CONTROLLER";
"B"
$PN"2"31;
"A"
$PN"1"2;
%"RES"
"1","(-7175,4475)","0","mstr_discrete","I46";
;
LOCATION"R2N17"
MATERIAL"CHIP"
WATTAGE"1/16W"
GROUP"PU_SKU_ID4"
PACK_TYPE"0402"
VALUE"2.7K"
PART_NUMBER"G21796-344"
TOLERANCE"1%"
BOM_COST"SM_CONTROLLER"
ROOM"BMC_MISC"
SEC"1"
SEC_TYPE"0402"
CDS_LIB"mstr_discrete"
CDS_SEC"1"
CDS_LOCATION"R2N17";
"B"
$PN"2"33;
"A"
$PN"1"2;
%"RES"
"1","(-7175,4075)","0","mstr_discrete","I47";
;
VALUE"2.7K"
LOCATION"R1U24"
PART_NUMBER"G21796-344"
TOLERANCE"1%"
WATTAGE"1/16W"
POP"NOPOP"
PACK_TYPE"0402"
MATERIAL"CHIP"
BOM_COST"SM_CONTROLLER"
ROOM"BMC_MISC"
SEC"1"
SEC_TYPE"0402"
CDS_LIB"mstr_discrete"
CDS_SEC"1"
CDS_LOCATION"R1U24";
"B"
$PN"2"13;
"A"
$PN"1"2;
%"RES"
"2","(-6325,3350)","0","mstr_discrete","I48";
;
CDS_SEC"1"
WATTAGE"1/16W"
TOLERANCE"1%"
MATERIAL"CHIP"
PACK_TYPE"0402"
PART_NUMBER"G21796-026"
GROUP"PD_SKU_ID3"
VALUE"1.00K"
LOCATION"R1U15"
SEC_TYPE"0402"
SEC"1"
ROOM"BMC_MISC"
BOM_COST"SM_CONTROLLER"
CDS_LIB"mstr_discrete"
CDS_LOCATION"R1U15";
"A"
$PN"1"32;
"B"
$PN"2"3;
%"RES"
"1","(-7400,1400)","0","mstr_discrete","I51";
;
VALUE"2.7K"
TOLERANCE"1%"
PACK_TYPE"0402"
LOCATION"R1T6"
PART_NUMBER"G21796-344"
WATTAGE"1/16W"
MATERIAL"CHIP"
CDS_SEC"1"
CDS_LIB"mstr_discrete"
SEC_TYPE"0402"
SEC"1"
ROOM"BMC_MISC"
BOM_COST"SM_CONTROLLER"
CDS_LOCATION"R1T6";
"B"
$PN"2"16;
"A"
$PN"1"1;
%"RES"
"2","(-6550,925)","0","mstr_discrete","I53";
;
PACK_TYPE"0402"
LOCATION"R1T12"
POP"NOPOP"
MATERIAL"CHIP"
WATTAGE"1/16W"
TOLERANCE"1%"
VALUE"1.00K"
PART_NUMBER"G21796-026"
CDS_LOCATION"R1T12"
ROOM"BMC_MISC"
CDS_LIB"mstr_discrete"
BOM_COST"SM_CONTROLLER"
SEC_TYPE"0402"
SEC"1"
CDS_SEC"1";
"A"
$PN"1"16;
"B"
$PN"2"12;
%"GND"
"1","(-1750,3175)","0","mstr_symbols","I55";
;
VOLTAGE"0.0V"
SIZE"1B"
CDS_LIB"mstr_symbols"
BODY_TYPE"PLUMBING"
HDL_POWER"GND";
"A\NAC"4;
%"P3V3_STBY"
"1","(-3400,4150)","0","mstr_symbols","I65";
;
CDS_LIB"mstr_symbols"
SIZE"1B"
VOLTAGE"3.3V"
BODY_TYPE"PLUMBING"
HDL_POWER"P3V3_STBY";
"G\NAC"5;
%"CAP_A"
"1","(-3400,3900)","0","dev_discrete","I66";
;
VOLTAGE"16V"
VALUE"0.1UF"
LOCATION"C6W14"
PACK_TYPE"0402V"
MATERIAL"X7R"
TOLERANCE"10%"
PART_NUMBER"A36096-030"
CDS_LOCATION"C6W14"
SEC"1"
SEC_TYPE"0402V"
ROOM"VDDQ_KLM_PWR_VR"
CDS_SEC"1"
CDS_LIB"dev_discrete";
"B"
$PN"2"6;
"A"
$PN"1"5;
%"GND"
"1","(-3400,3700)","0","mstr_symbols","I67";
;
VOLTAGE"0.0V"
SIZE"1B"
CDS_LIB"mstr_symbols"
BODY_TYPE"PLUMBING"
HDL_POWER"GND";
"A\NAC"6;
%"RES"
"2","(-6850,925)","0","mstr_discrete","I7";
;
CDS_SEC"1"
PART_NUMBER"G21796-026"
WATTAGE"1/16W"
TOLERANCE"1%"
MATERIAL"CHIP"
VALUE"1.00K"
PACK_TYPE"0402"
LOCATION"R1T11"
SEC"1"
BOM_COST"SM_CONTROLLER"
SEC_TYPE"0402"
ROOM"BMC_MISC"
CDS_LOCATION"R1T11"
CDS_LIB"mstr_discrete";
"A"
$PN"1"30;
"B"
$PN"2"12;
%"RES"
"2","(-1650,1800)","0","mstr_discrete","I76";
;
PACK_TYPE"0402"
PART_NUMBER"G21796-072"
MATERIAL"EMPTY"
WATTAGE"1/16W"
TOLERANCE"1%"
VALUE"4.75K"
LOCATION"R6W47"
CDS_LOCATION"R6W47"
CDS_LIB"mstr_discrete"
ROOM"HOT_SWAP"
NO_XNET_CONNECTION"1"
SEC"1"
SEC_TYPE"0402"
CDS_SEC"1";
"A"
$PN"1"25;
"B"
$PN"2"8;
%"RES"
"2","(-1650,2350)","2","mstr_discrete","I78";
;
CDS_SEC"1"
CDS_LOCATION"R6W44"
VALUE"4.75K"
TOLERANCE"1%"
MATERIAL"CHIP"
WATTAGE"1/16W"
PACK_TYPE"0402"
PART_NUMBER"G21796-072"
LOCATION"R6W44"
SEC_TYPE"0402"
SEC"1"
ROOM"CPU_FANS"
BOM_COST"SM_THERM"
CDS_LIB"mstr_discrete";
"A"
$PN"1"7;
"B"
$PN"2"25;
%"P3V3_STBY"
"1","(-2350,2650)","0","mstr_symbols","I81";
;
HDL_POWER"P3V3_STBY"
BODY_TYPE"PLUMBING"
SIZE"1B"
CDS_LIB"mstr_symbols"
VOLTAGE"3.3V";
"G\NAC"7;
%"GND"
"1","(-1650,1600)","0","mstr_symbols","I82";
;
HDL_POWER"GND"
BODY_TYPE"PLUMBING"
SIZE"1B"
CDS_LIB"mstr_symbols"
VOLTAGE"0.0V";
"A\NAC"8;
%"GND"
"1","(-2000,1600)","0","mstr_symbols","I84";
;
HDL_POWER"GND"
BODY_TYPE"PLUMBING"
VOLTAGE"0.0V"
CDS_LIB"mstr_symbols"
SIZE"1B";
"A\NAC"9;
%"GND"
"1","(-2350,1600)","0","mstr_symbols","I86";
;
HDL_POWER"GND"
BODY_TYPE"PLUMBING"
SIZE"1B"
CDS_LIB"mstr_symbols"
VOLTAGE"0.0V";
"A\NAC"10;
%"RES"
"2","(-1000,3750)","2","mstr_discrete","I87";
;
VALUE"4.75K"
LOCATION"R6W41"
MATERIAL"CHIP"
TOLERANCE"1%"
WATTAGE"1/16W"
PART_NUMBER"G21796-072"
PACK_TYPE"0402"
CDS_SEC"1"
SEC_TYPE"0402"
SEC"1"
ROOM"CPU_FANS"
BOM_COST"SM_THERM"
CDS_LIB"mstr_discrete"
CDS_LOCATION"R6W41";
"A"
$PN"1"11;
"B"
$PN"2"18;
%"P3V3_STBY"
"1","(-1000,3950)","0","mstr_symbols","I88";
;
HDL_POWER"P3V3_STBY"
BODY_TYPE"PLUMBING"
CDS_LIB"mstr_symbols"
SIZE"1B"
VOLTAGE"3.3V";
"G\NAC"11;
%"GND"
"1","(-6850,625)","0","mstr_symbols","I9";
;
HDL_POWER"GND"
BODY_TYPE"PLUMBING"
CDS_LIB"mstr_symbols"
SIZE"1B"
VOLTAGE"0.0V";
"A\NAC"12;
%"RES"
"2","(-2000,1800)","2","mstr_discrete","I93";
;
CDS_SEC"1"
CDS_LOCATION"R6W46"
VALUE"4.75K"
WATTAGE"1/16W"
TOLERANCE"1%"
LOCATION"R6W46"
MATERIAL"CHIP"
PART_NUMBER"G21796-072"
PACK_TYPE"0402"
SEC_TYPE"0402"
SEC"1"
BOM_COST"SM_THERM"
ROOM"CPU_FANS"
CDS_LIB"mstr_discrete";
"A"
$PN"1"29;
"B"
$PN"2"9;
%"RES"
"2","(-2350,1800)","2","mstr_discrete","I94";
;
CDS_SEC"1"
CDS_LOCATION"R6W45"
TOLERANCE"1%"
LOCATION"R6W45"
VALUE"4.75K"
WATTAGE"1/16W"
MATERIAL"CHIP"
PART_NUMBER"G21796-072"
PACK_TYPE"0402"
SEC_TYPE"0402"
SEC"1"
BOM_COST"SM_THERM"
ROOM"CPU_FANS"
CDS_LIB"mstr_discrete";
"A"
$PN"1"15;
"B"
$PN"2"10;
%"RES"
"2","(-2350,2350)","0","mstr_discrete","I95";
;
WATTAGE"1/16W"
LOCATION"R6W42"
VALUE"4.75K"
TOLERANCE"1%"
MATERIAL"EMPTY"
PART_NUMBER"G21796-072"
PACK_TYPE"0402"
CDS_SEC"1"
NO_XNET_CONNECTION"1"
ROOM"HOT_SWAP"
CDS_LIB"mstr_discrete"
SEC"1"
SEC_TYPE"0402"
CDS_LOCATION"R6W42";
"A"
$PN"1"7;
"B"
$PN"2"15;
%"RES"
"2","(-2000,2350)","0","mstr_discrete","I96";
;
PART_NUMBER"G21796-072"
LOCATION"R6W43"
TOLERANCE"1%"
MATERIAL"EMPTY"
WATTAGE"1/16W"
VALUE"4.75K"
PACK_TYPE"0402"
CDS_SEC"1"
CDS_LIB"mstr_discrete"
NO_XNET_CONNECTION"1"
ROOM"HOT_SWAP"
SEC"1"
SEC_TYPE"0402"
CDS_LOCATION"R6W43";
"A"
$PN"1"7;
"B"
$PN"2"29;
%"PCA9554PWR-GP"
"1","(-2150,3500)","0","w_hdl","I97";
;
CDS_SEC"1"
CDS_LOCATION"U6W11"
LOCATION"U6W11"
VALUE"PCA9554PWR-GP"
PACK_TYPE"DISCRET-G1"
SEC"1"
SEC_TYPE"DISCRET-G1"
CDS_LMAN_SYM_OUTLINE"-200,300,200,-300"
CDS_LIB"w_hdl"
PART_NUMBER"71.09554.C0W";
"VCC"
$PN"16"5;
"SDA"
$PN"15"26;
"SCL"
$PN"14"23;
"INT# \B"
$PN"13"18;
"P7"
$PN"12"0;
"P6"
$PN"11"0;
"P5"
$PN"10"0;
"P4"
$PN"9"0;
"GND"
$PN"8"4;
"P3"
$PN"7"21;
"P2"
$PN"6"22;
"P1"
$PN"5"27;
"P0"
$PN"4"28;
"A2"
$PN"3"19;
"A1"
$PN"2"20;
"A0"
$PN"1"24;
END.
